(kicad_pcb
	(version 20260206)
	(generator "pcbnew")
	(generator_version "10.0")
	(general
		(thickness 1.6)
		(legacy_teardrops no)
	)
	(paper "A4")
	(title_block
		(title "01162023_DA0F0TEBIF0_F0T_Expander_BD_F_brd_V02_OCP.brd")
		(comment 1 "Grand Teton / footprints 1157-1161 of 9728")
	)
	(layers
		(0 "F.Cu" signal "TOP")
		(4 "In1.Cu" signal "GND")
		(6 "In2.Cu" signal "VCC")
		(8 "In3.Cu" signal "VCC1")
		(10 "In4.Cu" signal "GND1")
		(12 "In5.Cu" signal "IN1")
		(14 "In6.Cu" signal "GND2")
		(16 "In7.Cu" signal "IN2")
		(18 "In8.Cu" signal "GND3")
		(20 "In9.Cu" signal "IN3")
		(22 "In10.Cu" signal "GND4")
		(24 "In11.Cu" signal "IN4")
		(26 "In12.Cu" signal "GND5")
		(28 "In13.Cu" signal "IN5")
		(30 "In14.Cu" signal "GND6")
		(32 "In15.Cu" signal "IN6")
		(34 "In16.Cu" signal "GND7")
		(2 "B.Cu" signal "BOTTOM")
		(9 "F.Adhes" user "F.Adhesive")
		(11 "B.Adhes" user "B.Adhesive")
		(13 "F.Paste" user "Package Geometry/Pastemask Top")
		(15 "B.Paste" user "Package Geometry/Pastemask Bottom")
		(5 "F.SilkS" user "Ref Des/Silkscreen Top")
		(7 "B.SilkS" user "Ref Des/Silkscreen Bottom")
		(1 "F.Mask" user "Board Geometry/Soldermask Top")
		(3 "B.Mask" user "Board Geometry/Soldermask Bottom")
		(17 "Dwgs.User" user "User.Drawings")
		(19 "Cmts.User" user "User.Comments")
		(21 "Eco1.User" user "User.Eco1")
		(23 "Eco2.User" user "User.Eco2")
		(25 "Edge.Cuts" user "Board Geometry/Outline")
		(27 "Margin" user)
		(31 "F.CrtYd" user "Package Geometry/Place Bound Top")
		(29 "B.CrtYd" user "Package Geometry/Place Bound Bottom")
		(35 "F.Fab" user "Ref Des/Assembly Top")
		(33 "B.Fab" user "Ref Des/Assembly Bottom")
	)
	(footprint ""
		(layer "F.Cu")
		(at 359.156 -172.974)
		(property "Reference" "R4670"
			(at 0 0 0)
			(layer "F.SilkS")
			(hide yes)
			(effects
				(font
					(size 1.27 1.27)
				)
			)
		)
		(property "Value" ""
			(at 0 0 0)
			(layer "F.Fab")
			(effects
				(font
					(size 1.27 1.27)
				)
			)
		)
		(duplicate_pad_numbers_are_jumpers no)
		(fp_line
			(start -0.7874 -0.4064)
			(end 0.7874 -0.4064)
			(stroke
				(width 0.1524)
				(type default)
			)
			(layer "F.SilkS")
		)
		(fp_line
			(start -0.7874 0.4064)
			(end -0.7874 -0.4064)
			(stroke
				(width 0.1524)
				(type default)
			)
			(layer "F.SilkS")
		)
		(fp_line
			(start 0.7874 -0.4064)
			(end 0.7874 0.4064)
			(stroke
				(width 0.1524)
				(type default)
			)
			(layer "F.SilkS")
		)
		(fp_line
			(start 0.7874 0.4064)
			(end -0.7874 0.4064)
			(stroke
				(width 0.1524)
				(type default)
			)
			(layer "F.SilkS")
		)
		(fp_line
			(start -0.67945 -0.305054)
			(end -0.12065 -0.305054)
			(stroke
				(width 0.1)
				(type default)
			)
			(layer "F.Fab")
		)
		(fp_line
			(start -0.67945 0.3048)
			(end -0.67945 -0.305054)
			(stroke
				(width 0.1)
				(type default)
			)
			(layer "F.Fab")
		)
		(fp_line
			(start -0.12065 -0.305054)
			(end -0.12065 -0.2794)
			(stroke
				(width 0.1)
				(type default)
			)
			(layer "F.Fab")
		)
		(fp_line
			(start -0.12065 -0.2794)
			(end 0.12065 -0.2794)
			(stroke
				(width 0.1)
				(type default)
			)
			(layer "F.Fab")
		)
		(fp_line
			(start -0.12065 0.2794)
			(end -0.12065 0.3048)
			(stroke
				(width 0.1)
				(type default)
			)
			(layer "F.Fab")
		)
		(fp_line
			(start -0.12065 0.3048)
			(end -0.67945 0.3048)
			(stroke
				(width 0.1)
				(type default)
			)
			(layer "F.Fab")
		)
		(fp_line
			(start 0.120396 0.2794)
			(end -0.12065 0.2794)
			(stroke
				(width 0.1)
				(type default)
			)
			(layer "F.Fab")
		)
		(fp_line
			(start 0.120396 0.3048)
			(end 0.120396 0.2794)
			(stroke
				(width 0.1)
				(type default)
			)
			(layer "F.Fab")
		)
		(fp_line
			(start 0.12065 -0.3048)
			(end 0.67945 -0.3048)
			(stroke
				(width 0.1)
				(type default)
			)
			(layer "F.Fab")
		)
		(fp_line
			(start 0.12065 -0.2794)
			(end 0.12065 -0.3048)
			(stroke
				(width 0.1)
				(type default)
			)
			(layer "F.Fab")
		)
		(fp_line
			(start 0.67945 -0.3048)
			(end 0.67945 0.3048)
			(stroke
				(width 0.1)
				(type default)
			)
			(layer "F.Fab")
		)
		(fp_line
			(start 0.67945 0.3048)
			(end 0.120396 0.3048)
			(stroke
				(width 0.1)
				(type default)
			)
			(layer "F.Fab")
		)
		(pad "1" smd circle
			(at -0.40005 0)
			(size 0 0)
			(layers "F.Cu" "F.Mask" "F.Paste")
			(net "P3V3_AUX")
		)
		(pad "2" smd circle
			(at 0.40005 0)
			(size 0 0)
			(layers "F.Cu" "F.Mask" "F.Paste")
			(net "RST_PEX_SSD7_PERST_R_N")
		)
	)
	(footprint ""
		(layer "F.Cu")
		(at 219.202 -208.788 180)
		(property "Reference" "C2555"
			(at 0 0 180)
			(layer "F.SilkS")
			(hide yes)
			(effects
				(font
					(size 1.27 1.27)
				)
			)
		)
		(property "Value" ""
			(at 0 0 180)
			(layer "F.Fab")
			(effects
				(font
					(size 1.27 1.27)
				)
			)
		)
		(duplicate_pad_numbers_are_jumpers no)
		(fp_line
			(start 0.7874 0.4064)
			(end -0.7874 0.4064)
			(stroke
				(width 0.1524)
				(type default)
			)
			(layer "F.SilkS")
		)
		(fp_line
			(start 0.7874 -0.4064)
			(end 0.7874 0.4064)
			(stroke
				(width 0.1524)
				(type default)
			)
			(layer "F.SilkS")
		)
		(fp_line
			(start -0.7874 0.4064)
			(end -0.7874 -0.4064)
			(stroke
				(width 0.1524)
				(type default)
			)
			(layer "F.SilkS")
		)
		(fp_line
			(start -0.7874 -0.4064)
			(end 0.7874 -0.4064)
			(stroke
				(width 0.1524)
				(type default)
			)
			(layer "F.SilkS")
		)
		(fp_line
			(start 0.67945 0.3048)
			(end 0.120396 0.3048)
			(stroke
				(width 0.1)
				(type default)
			)
			(layer "F.Fab")
		)
		(fp_line
			(start 0.67945 -0.3048)
			(end 0.67945 0.3048)
			(stroke
				(width 0.1)
				(type default)
			)
			(layer "F.Fab")
		)
		(fp_line
			(start 0.12065 -0.2794)
			(end 0.12065 -0.3048)
			(stroke
				(width 0.1)
				(type default)
			)
			(layer "F.Fab")
		)
		(fp_line
			(start 0.12065 -0.3048)
			(end 0.67945 -0.3048)
			(stroke
				(width 0.1)
				(type default)
			)
			(layer "F.Fab")
		)
		(fp_line
			(start 0.120396 0.3048)
			(end 0.120396 0.2794)
			(stroke
				(width 0.1)
				(type default)
			)
			(layer "F.Fab")
		)
		(fp_line
			(start 0.120396 0.2794)
			(end -0.12065 0.2794)
			(stroke
				(width 0.1)
				(type default)
			)
			(layer "F.Fab")
		)
		(fp_line
			(start -0.12065 0.3048)
			(end -0.67945 0.3048)
			(stroke
				(width 0.1)
				(type default)
			)
			(layer "F.Fab")
		)
		(fp_line
			(start -0.12065 0.2794)
			(end -0.12065 0.3048)
			(stroke
				(width 0.1)
				(type default)
			)
			(layer "F.Fab")
		)
		(fp_line
			(start -0.12065 -0.2794)
			(end 0.12065 -0.2794)
			(stroke
				(width 0.1)
				(type default)
			)
			(layer "F.Fab")
		)
		(fp_line
			(start -0.12065 -0.305054)
			(end -0.12065 -0.2794)
			(stroke
				(width 0.1)
				(type default)
			)
			(layer "F.Fab")
		)
		(fp_line
			(start -0.67945 0.3048)
			(end -0.67945 -0.305054)
			(stroke
				(width 0.1)
				(type default)
			)
			(layer "F.Fab")
		)
		(fp_line
			(start -0.67945 -0.305054)
			(end -0.12065 -0.305054)
			(stroke
				(width 0.1)
				(type default)
			)
			(layer "F.Fab")
		)
		(pad "1" smd circle
			(at -0.40005 0 180)
			(size 0 0)
			(layers "F.Cu" "F.Mask" "F.Paste")
			(net "GND")
		)
		(pad "2" smd circle
			(at 0.40005 0 180)
			(size 0 0)
			(layers "F.Cu" "F.Mask" "F.Paste")
			(net "P3V3_NIC4")
		)
	)
	(footprint ""
		(layer "F.Cu")
		(at 19.838924 -167.891714 -90)
		(property "Reference" "PC17"
			(at 0 0 270)
			(layer "F.SilkS")
			(hide yes)
			(effects
				(font
					(size 1.27 1.27)
				)
			)
		)
		(property "Value" ""
			(at 0 0 270)
			(layer "F.Fab")
			(effects
				(font
					(size 1.27 1.27)
				)
			)
		)
		(duplicate_pad_numbers_are_jumpers no)
		(fp_line
			(start -0.7874 0.4064)
			(end -0.7874 -0.4064)
			(stroke
				(width 0.1524)
				(type default)
			)
			(layer "F.SilkS")
		)
		(fp_line
			(start 0.7874 0.4064)
			(end -0.7874 0.4064)
			(stroke
				(width 0.1524)
				(type default)
			)
			(layer "F.SilkS")
		)
		(fp_line
			(start -0.7874 -0.4064)
			(end 0.7874 -0.4064)
			(stroke
				(width 0.1524)
				(type default)
			)
			(layer "F.SilkS")
		)
		(fp_line
			(start 0.7874 -0.4064)
			(end 0.7874 0.4064)
			(stroke
				(width 0.1524)
				(type default)
			)
			(layer "F.SilkS")
		)
		(fp_line
			(start -0.67945 0.3048)
			(end -0.67945 -0.305054)
			(stroke
				(width 0.1)
				(type default)
			)
			(layer "F.Fab")
		)
		(fp_line
			(start -0.12065 0.3048)
			(end -0.67945 0.3048)
			(stroke
				(width 0.1)
				(type default)
			)
			(layer "F.Fab")
		)
		(fp_line
			(start 0.120396 0.3048)
			(end 0.120396 0.2794)
			(stroke
				(width 0.1)
				(type default)
			)
			(layer "F.Fab")
		)
		(fp_line
			(start 0.67945 0.3048)
			(end 0.120396 0.3048)
			(stroke
				(width 0.1)
				(type default)
			)
			(layer "F.Fab")
		)
		(fp_line
			(start -0.12065 0.2794)
			(end -0.12065 0.3048)
			(stroke
				(width 0.1)
				(type default)
			)
			(layer "F.Fab")
		)
		(fp_line
			(start 0.120396 0.2794)
			(end -0.12065 0.2794)
			(stroke
				(width 0.1)
				(type default)
			)
			(layer "F.Fab")
		)
		(fp_line
			(start -0.12065 -0.2794)
			(end 0.12065 -0.2794)
			(stroke
				(width 0.1)
				(type default)
			)
			(layer "F.Fab")
		)
		(fp_line
			(start 0.12065 -0.2794)
			(end 0.12065 -0.3048)
			(stroke
				(width 0.1)
				(type default)
			)
			(layer "F.Fab")
		)
		(fp_line
			(start 0.12065 -0.3048)
			(end 0.67945 -0.3048)
			(stroke
				(width 0.1)
				(type default)
			)
			(layer "F.Fab")
		)
		(fp_line
			(start 0.67945 -0.3048)
			(end 0.67945 0.3048)
			(stroke
				(width 0.1)
				(type default)
			)
			(layer "F.Fab")
		)
		(fp_line
			(start -0.67945 -0.305054)
			(end -0.12065 -0.305054)
			(stroke
				(width 0.1)
				(type default)
			)
			(layer "F.Fab")
		)
		(fp_line
			(start -0.12065 -0.305054)
			(end -0.12065 -0.2794)
			(stroke
				(width 0.1)
				(type default)
			)
			(layer "F.Fab")
		)
		(pad "1" smd circle
			(at -0.40005 0 270)
			(size 0 0)
			(layers "F.Cu" "F.Mask" "F.Paste")
			(net "SW_P12V_P5V_AUX_FLT")
		)
		(pad "2" smd circle
			(at 0.40005 0 270)
			(size 0 0)
			(layers "F.Cu" "F.Mask" "F.Paste")
			(net "GND")
		)
	)
	(footprint ""
		(layer "F.Cu")
		(at 97.738438 -44.341542 90)
		(property "Reference" "C308"
			(at 0 0 90)
			(layer "F.SilkS")
			(hide yes)
			(effects
				(font
					(size 1.27 1.27)
				)
			)
		)
		(property "Value" ""
			(at 0 0 90)
			(layer "F.Fab")
			(effects
				(font
					(size 1.27 1.27)
				)
			)
		)
		(duplicate_pad_numbers_are_jumpers no)
		(fp_line
			(start 0.7874 -0.4064)
			(end 0.7874 0.4064)
			(stroke
				(width 0.1524)
				(type default)
			)
			(layer "F.SilkS")
		)
		(fp_line
			(start -0.7874 -0.4064)
			(end 0.7874 -0.4064)
			(stroke
				(width 0.1524)
				(type default)
			)
			(layer "F.SilkS")
		)
		(fp_line
			(start 0.7874 0.4064)
			(end -0.7874 0.4064)
			(stroke
				(width 0.1524)
				(type default)
			)
			(layer "F.SilkS")
		)
		(fp_line
			(start -0.7874 0.4064)
			(end -0.7874 -0.4064)
			(stroke
				(width 0.1524)
				(type default)
			)
			(layer "F.SilkS")
		)
		(fp_line
			(start -0.12065 -0.305054)
			(end -0.12065 -0.2794)
			(stroke
				(width 0.1)
				(type default)
			)
			(layer "F.Fab")
		)
		(fp_line
			(start -0.67945 -0.305054)
			(end -0.12065 -0.305054)
			(stroke
				(width 0.1)
				(type default)
			)
			(layer "F.Fab")
		)
		(fp_line
			(start 0.67945 -0.3048)
			(end 0.67945 0.3048)
			(stroke
				(width 0.1)
				(type default)
			)
			(layer "F.Fab")
		)
		(fp_line
			(start 0.12065 -0.3048)
			(end 0.67945 -0.3048)
			(stroke
				(width 0.1)
				(type default)
			)
			(layer "F.Fab")
		)
		(fp_line
			(start 0.12065 -0.2794)
			(end 0.12065 -0.3048)
			(stroke
				(width 0.1)
				(type default)
			)
			(layer "F.Fab")
		)
		(fp_line
			(start -0.12065 -0.2794)
			(end 0.12065 -0.2794)
			(stroke
				(width 0.1)
				(type default)
			)
			(layer "F.Fab")
		)
		(fp_line
			(start 0.120396 0.2794)
			(end -0.12065 0.2794)
			(stroke
				(width 0.1)
				(type default)
			)
			(layer "F.Fab")
		)
		(fp_line
			(start -0.12065 0.2794)
			(end -0.12065 0.3048)
			(stroke
				(width 0.1)
				(type default)
			)
			(layer "F.Fab")
		)
		(fp_line
			(start 0.67945 0.3048)
			(end 0.120396 0.3048)
			(stroke
				(width 0.1)
				(type default)
			)
			(layer "F.Fab")
		)
		(fp_line
			(start 0.120396 0.3048)
			(end 0.120396 0.2794)
			(stroke
				(width 0.1)
				(type default)
			)
			(layer "F.Fab")
		)
		(fp_line
			(start -0.12065 0.3048)
			(end -0.67945 0.3048)
			(stroke
				(width 0.1)
				(type default)
			)
			(layer "F.Fab")
		)
		(fp_line
			(start -0.67945 0.3048)
			(end -0.67945 -0.305054)
			(stroke
				(width 0.1)
				(type default)
			)
			(layer "F.Fab")
		)
		(pad "1" smd circle
			(at -0.40005 0 90)
			(size 0 0)
			(layers "F.Cu" "F.Mask" "F.Paste")
			(net "P12V_SSD3_VIN_P")
		)
		(pad "2" smd circle
			(at 0.40005 0 90)
			(size 0 0)
			(layers "F.Cu" "F.Mask" "F.Paste")
			(net "P12V_SSD3_VIN_N")
		)
	)
	(footprint ""
		(layer "F.Cu")
		(at 377.949714 -320.900044)
		(property "Reference" "H95"
			(at -6.547358 -7.430008 0)
			(unlocked yes)
			(layer "F.SilkS")
			(effects
				(font
					(size 0.7874 0.5842)
					(thickness 0.1524)
				)
				(justify left)
			)
		)
		(property "Value" ""
			(at 0 0 0)
			(layer "F.Fab")
			(effects
				(font
					(size 1.27 1.27)
				)
			)
		)
		(duplicate_pad_numbers_are_jumpers no)
		(fp_arc
			(start 5.586984 5.725922)
			(mid -7.372531 -3.10691)
			(end 7.999984 0)
			(stroke
				(width 0.1524)
				(type default)
			)
			(layer "F.SilkS")
		)
		(fp_arc
			(start -6.82498 -4.172966)
			(mid 2.167755 -7.700511)
			(end 7.999984 0)
			(stroke
				(width 0.1524)
				(type default)
			)
			(layer "B.SilkS")
		)
		(fp_arc
			(start -6.018022 5.2705)
			(mid -7.86291 1.472295)
			(end -7.51713 -2.736088)
			(stroke
				(width 0.1524)
				(type default)
			)
			(layer "B.SilkS")
		)
		(fp_arc
			(start 5.690108 5.623306)
			(mid 1.770476 7.801371)
			(end -2.705354 7.528306)
			(stroke
				(width 0.1524)
				(type default)
			)
			(layer "B.SilkS")
		)
		(fp_arc
			(start 7.999984 0)
			(mid 7.997304 0.206063)
			(end 7.989316 0.411988)
			(stroke
				(width 0.1524)
				(type default)
			)
			(layer "B.SilkS")
		)
		(fp_circle
			(center 0 0)
			(end 7.999984 0)
			(stroke
				(width 0.1)
				(type default)
			)
			(fill no)
			(layer "B.Fab")
		)
		(fp_circle
			(center 0 0)
			(end 7.999984 0)
			(stroke
				(width 0.1)
				(type default)
			)
			(fill no)
			(layer "F.Fab")
		)
		(pad "" np_thru_hole circle
			(at 0 0)
			(size 4.5212 4.5212)
			(drill 4.5212)
			(layers "*.Cu" "*.Mask")
			(clearance 0.381)
			(thermal_gap 0.381)
		)
		(pad "2" thru_hole circle
			(at 3.6322 0)
			(size 0.762 0.762)
			(drill 0.5588)
			(layers "*.Cu" "*.Mask")
			(remove_unused_layers no)
			(net "GND")
			(clearance 0.1524)
			(thermal_gap 0.1524)
		)
		(pad "3" thru_hole circle
			(at 2.568448 -2.568448)
			(size 0.762 0.762)
			(drill 0.5588)
			(layers "*.Cu" "*.Mask")
			(remove_unused_layers no)
			(net "GND")
			(clearance 0.1524)
			(thermal_gap 0.1524)
		)
		(pad "4" thru_hole circle
			(at 0 -3.6322)
			(size 0.762 0.762)
			(drill 0.5588)
			(layers "*.Cu" "*.Mask")
			(remove_unused_layers no)
			(net "GND")
			(clearance 0.1524)
			(thermal_gap 0.1524)
		)
		(pad "5" thru_hole circle
			(at -2.568448 -2.568448)
			(size 0.762 0.762)
			(drill 0.5588)
			(layers "*.Cu" "*.Mask")
			(remove_unused_layers no)
			(net "GND")
			(clearance 0.1524)
			(thermal_gap 0.1524)
		)
		(pad "6" thru_hole circle
			(at -3.6322 0)
			(size 0.762 0.762)
			(drill 0.5588)
			(layers "*.Cu" "*.Mask")
			(remove_unused_layers no)
			(net "GND")
			(clearance 0.1524)
			(thermal_gap 0.1524)
		)
		(pad "7" thru_hole circle
			(at -2.568448 2.568448)
			(size 0.762 0.762)
			(drill 0.5588)
			(layers "*.Cu" "*.Mask")
			(remove_unused_layers no)
			(net "GND")
			(clearance 0.1524)
			(thermal_gap 0.1524)
		)
		(pad "8" thru_hole circle
			(at 0 3.6322)
			(size 0.762 0.762)
			(drill 0.5588)
			(layers "*.Cu" "*.Mask")
			(remove_unused_layers no)
			(net "GND")
			(clearance 0.1524)
			(thermal_gap 0.1524)
		)
		(pad "9" thru_hole circle
			(at 2.568448 2.568448)
			(size 0.762 0.762)
			(drill 0.5588)
			(layers "*.Cu" "*.Mask")
			(remove_unused_layers no)
			(net "GND")
			(clearance 0.1524)
			(thermal_gap 0.1524)
		)
		(zone
			(layer "F.Cu")
			(hatch none 0.5)
			(connect_pads
				(clearance 0)
			)
			(min_thickness 0.25)
			(keepout
				(tracks not_allowed)
				(vias allowed)
				(pads allowed)
				(copperpour not_allowed)
				(footprints allowed)
			)
			(placement
				(enabled no)
				(sheetname "")
			)
			(fill
				(thermal_gap 0.5)
				(thermal_bridge_width 0.5)
				(island_removal_mode 0)
			)
			(polygon
				(pts
					(arc
						(start 377.949714 -312.90006)
						(mid 369.94973 -320.900044)
						(end 377.949714 -328.900028)
					)
					(arc
						(start 377.949714 -325.649844)
						(mid 373.199914 -320.900044)
						(end 377.949714 -316.150244)
					)
				)
			)
		)
		(zone
			(layer "F.Cu")
			(hatch none 0.5)
			(connect_pads
				(clearance 0)
			)
			(min_thickness 0.25)
			(keepout
				(tracks not_allowed)
				(vias allowed)
				(pads allowed)
				(copperpour not_allowed)
				(footprints allowed)
			)
			(placement
				(enabled no)
				(sheetname "")
			)
			(fill
				(thermal_gap 0.5)
				(thermal_bridge_width 0.5)
				(island_removal_mode 0)
			)
			(polygon
				(pts
					(arc
						(start 377.949714 -312.90006)
						(mid 385.949698 -320.900044)
						(end 377.949714 -328.900028)
					)
					(arc
						(start 377.949714 -325.649844)
						(mid 382.699514 -320.900044)
						(end 377.949714 -316.150244)
					)
				)
			)
		)
		(zone
			(layers "F.Cu" "B.Cu" "In1.Cu" "In2.Cu" "In3.Cu" "In4.Cu" "In5.Cu" "In6.Cu"
				"In7.Cu" "In8.Cu" "In9.Cu" "In10.Cu" "In11.Cu" "In12.Cu" "In13.Cu" "In14.Cu"
				"In15.Cu" "In16.Cu"
			)
			(hatch none 0.5)
			(connect_pads
				(clearance 0)
			)
			(min_thickness 0.25)
			(keepout
				(tracks not_allowed)
				(vias allowed)
				(pads allowed)
				(copperpour not_allowed)
				(footprints allowed)
			)
			(placement
				(enabled no)
				(sheetname "")
			)
			(fill
				(thermal_gap 0.5)
				(thermal_bridge_width 0.5)
				(island_removal_mode 0)
			)
			(polygon
				(pts
					(arc
						(start 380.715774 -320.900044)
						(mid 375.183654 -320.900044)
						(end 380.715774 -320.900044)
					)
				)
			)
		)
		(zone
			(layer "B.Cu")
			(hatch none 0.5)
			(connect_pads
				(clearance 0)
			)
			(min_thickness 0.25)
			(keepout
				(tracks not_allowed)
				(vias allowed)
				(pads allowed)
				(copperpour not_allowed)
				(footprints allowed)
			)
			(placement
				(enabled no)
				(sheetname "")
			)
			(fill
				(thermal_gap 0.5)
				(thermal_bridge_width 0.5)
				(island_removal_mode 0)
			)
			(polygon
				(pts
					(arc
						(start 377.949714 -315.896244)
						(mid 372.945914 -320.900044)
						(end 377.949714 -325.903844)
					)
					(arc
						(start 377.949714 -325.421244)
						(mid 373.428514 -320.900044)
						(end 377.949714 -316.378844)
					)
				)
			)
		)
		(zone
			(layer "B.Cu")
			(hatch none 0.5)
			(connect_pads
				(clearance 0)
			)
			(min_thickness 0.25)
			(keepout
				(tracks not_allowed)
				(vias allowed)
				(pads allowed)
				(copperpour not_allowed)
				(footprints allowed)
			)
			(placement
				(enabled no)
				(sheetname "")
			)
			(fill
				(thermal_gap 0.5)
				(thermal_bridge_width 0.5)
				(island_removal_mode 0)
			)
			(polygon
				(pts
					(arc
						(start 377.949714 -315.896244)
						(mid 382.953514 -320.900044)
						(end 377.949714 -325.903844)
					)
					(arc
						(start 377.949714 -325.421244)
						(mid 382.470914 -320.900044)
						(end 377.949714 -316.378844)
					)
				)
			)
		)
	)
)
